# BASEBOARD_FAB2 (Tioga Pass) — schematic netlist excerpt (pin names and nets, part order shuffled) for the footprints in the layout excerpt that follows; sources: Cadence DE-HDL packaged netlist, KiCad conversion of Wiwynn_Tioga_Pass_MB.brd

C5M3  CAP_A  47UF 4V 20% X5R  pkg 0603V  page 220 : A = PVDDQ_DEF ; B = GND
C4L4  CAP  10UF 4V 20% X6S  pkg 0603LF  page 232 : A = PVPP_DEF ; B = GND
R3P16  RES  1.5K 1% CHIP  pkg 0402  page 211 : A = VR_PVCCIO_CPU0_VINSEN ; B = GND

(kicad_pcb
	(version 20260206)
	(generator "pcbnew")
	(generator_version "10.0")
	(general
		(thickness 1.6)
		(legacy_teardrops no)
	)
	(paper "A4")
	(title_block
		(title "Wiwynn_Tioga_Pass_MB.brd")
		(comment 1 "Tioga Pass / footprints 3916-3918 of 4770")
	)
	(layers
		(0 "F.Cu" signal "TOP")
		(4 "In1.Cu" signal "L2GND")
		(6 "In2.Cu" signal "L3")
		(8 "In3.Cu" signal "L4GND")
		(10 "In4.Cu" signal "L5")
		(12 "In5.Cu" signal "L6GND")
		(14 "In6.Cu" signal "L7VCC")
		(16 "In7.Cu" signal "L8VCC")
		(18 "In8.Cu" signal "L9GND")
		(20 "In9.Cu" signal "L10")
		(22 "In10.Cu" signal "L11GND")
		(24 "In11.Cu" signal "L12")
		(26 "In12.Cu" signal "L13GND")
		(2 "B.Cu" signal "BOTTOM")
		(9 "F.Adhes" user "F.Adhesive")
		(11 "B.Adhes" user "B.Adhesive")
		(13 "F.Paste" user "Package Geometry/Pastemask Top")
		(15 "B.Paste" user "Package Geometry/Pastemask Bottom")
		(5 "F.SilkS" user "Ref Des/Silkscreen Top")
		(7 "B.SilkS" user "Ref Des/Silkscreen Bottom")
		(1 "F.Mask" user "Board Geometry/Soldermask Top")
		(3 "B.Mask" user "Board Geometry/Soldermask Bottom")
		(17 "Dwgs.User" user "User.Drawings")
		(19 "Cmts.User" user "User.Comments")
		(21 "Eco1.User" user "User.Eco1")
		(23 "Eco2.User" user "User.Eco2")
		(25 "Edge.Cuts" user "Board Geometry/Outline")
		(27 "Margin" user)
		(31 "F.CrtYd" user "Package Geometry/Place Bound Top")
		(29 "B.CrtYd" user "Package Geometry/Place Bound Bottom")
		(35 "F.Fab" user "Ref Des/Assembly Top")
		(33 "B.Fab" user "Ref Des/Assembly Bottom")
	)
	(footprint ""
		(layer "B.Cu")
		(at 350.9772 -86.741 90)
		(property "Reference" "R3P16"
			(at 0 0 90)
			(layer "B.SilkS")
			(hide yes)
			(effects
				(font
					(size 1.27 1.27)
				)
				(justify mirror)
			)
		)
		(property "Value" ""
			(at 0 0 90)
			(layer "B.Fab")
			(effects
				(font
					(size 1.27 1.27)
				)
				(justify mirror)
			)
		)
		(duplicate_pad_numbers_are_jumpers no)
		(fp_poly
			(pts
				(xy 0.2794 -0.1016) (xy -0.2794 -0.1016) (xy -0.2794 0.9906) (xy 0.2794 0.9906)
			)
			(stroke
				(width 0)
				(type default)
			)
			(fill no)
			(layer "B.CrtYd")
		)
		(fp_line
			(start 0.2794 -0.1016)
			(end 0.2794 0.9906)
			(stroke
				(width 0.1)
				(type default)
			)
			(layer "B.Fab")
		)
		(fp_line
			(start -0.2794 -0.1016)
			(end 0.2794 -0.1016)
			(stroke
				(width 0.1)
				(type default)
			)
			(layer "B.Fab")
		)
		(fp_line
			(start 0.2794 0.9906)
			(end -0.2794 0.9906)
			(stroke
				(width 0.1)
				(type default)
			)
			(layer "B.Fab")
		)
		(fp_line
			(start -0.2794 0.9906)
			(end -0.2794 -0.1016)
			(stroke
				(width 0.1)
				(type default)
			)
			(layer "B.Fab")
		)
		(pad "1" smd rect
			(at 0 0 270)
			(size 0.508 0.508)
			(layers "B.Cu" "B.Mask" "B.Paste")
			(net "VR_PVCCIO_CPU0_VINSEN")
		)
		(pad "2" smd rect
			(at 0 0.889 270)
			(size 0.508 0.508)
			(layers "B.Cu" "B.Mask" "B.Paste")
			(net "GND")
		)
		(zone
			(layer "B.Cu")
			(hatch none 0.5)
			(connect_pads
				(clearance 0)
			)
			(min_thickness 0.25)
			(keepout
				(tracks allowed)
				(vias not_allowed)
				(pads allowed)
				(copperpour not_allowed)
				(footprints allowed)
			)
			(placement
				(enabled no)
				(sheetname "")
			)
			(fill
				(thermal_gap 0.5)
				(thermal_bridge_width 0.5)
				(island_removal_mode 0)
			)
			(polygon
				(pts
					(xy 351.2312 -86.995) (xy 351.2312 -86.487) (xy 351.6122 -86.487) (xy 351.6122 -86.995)
				)
			)
		)
		(zone
			(layer "B.Cu")
			(hatch none 0.5)
			(connect_pads
				(clearance 0)
			)
			(min_thickness 0.25)
			(keepout
				(tracks not_allowed)
				(vias allowed)
				(pads allowed)
				(copperpour not_allowed)
				(footprints allowed)
			)
			(placement
				(enabled no)
				(sheetname "")
			)
			(fill
				(thermal_gap 0.5)
				(thermal_bridge_width 0.5)
				(island_removal_mode 0)
			)
			(polygon
				(pts
					(xy 351.6122 -86.995) (xy 351.6122 -86.487) (xy 351.2312 -86.487) (xy 351.2312 -86.995)
				)
			)
		)
	)
	(footprint ""
		(layer "B.Cu")
		(at 265.698732 -135.4074 90)
		(property "Reference" "C5M3"
			(at 0 0 90)
			(layer "B.SilkS")
			(hide yes)
			(effects
				(font
					(size 1.27 1.27)
				)
				(justify mirror)
			)
		)
		(property "Value" ""
			(at 0 0 90)
			(layer "B.Fab")
			(effects
				(font
					(size 1.27 1.27)
				)
				(justify mirror)
			)
		)
		(duplicate_pad_numbers_are_jumpers no)
		(fp_rect
			(start 0.500126 1.598422)
			(end -0.500126 -0.201422)
			(stroke
				(width 0)
				(type default)
			)
			(fill no)
			(layer "B.CrtYd")
		)
		(fp_line
			(start 0.500126 -0.201422)
			(end -0.500126 -0.201422)
			(stroke
				(width 0.1)
				(type default)
			)
			(layer "B.Fab")
		)
		(fp_line
			(start -0.500126 -0.201422)
			(end -0.500126 1.598422)
			(stroke
				(width 0.1)
				(type default)
			)
			(layer "B.Fab")
		)
		(fp_line
			(start 0.500126 1.598422)
			(end 0.500126 -0.201422)
			(stroke
				(width 0.1)
				(type default)
			)
			(layer "B.Fab")
		)
		(fp_line
			(start -0.500126 1.598422)
			(end 0.500126 1.598422)
			(stroke
				(width 0.1)
				(type default)
			)
			(layer "B.Fab")
		)
		(pad "1" smd rect
			(at 0 0)
			(size 0.889 0.9906)
			(layers "B.Cu" "B.Mask" "B.Paste")
			(net "PVDDQ_DEF")
		)
		(pad "2" smd rect
			(at 0 1.397)
			(size 0.889 0.9906)
			(layers "B.Cu" "B.Mask" "B.Paste")
			(net "GND")
		)
		(zone
			(layer "B.Cu")
			(hatch none 0.5)
			(connect_pads
				(clearance 0)
			)
			(min_thickness 0.25)
			(keepout
				(tracks not_allowed)
				(vias allowed)
				(pads allowed)
				(copperpour not_allowed)
				(footprints allowed)
			)
			(placement
				(enabled no)
				(sheetname "")
			)
			(fill
				(thermal_gap 0.5)
				(thermal_bridge_width 0.5)
				(island_removal_mode 0)
			)
			(polygon
				(pts
					(xy 266.651232 -135.9027) (xy 266.143232 -135.9027) (xy 266.143232 -134.9121) (xy 266.651232 -134.9121)
				)
			)
		)
		(zone
			(layer "B.Cu")
			(hatch none 0.5)
			(connect_pads
				(clearance 0)
			)
			(min_thickness 0.25)
			(keepout
				(tracks allowed)
				(vias not_allowed)
				(pads allowed)
				(copperpour not_allowed)
				(footprints allowed)
			)
			(placement
				(enabled no)
				(sheetname "")
			)
			(fill
				(thermal_gap 0.5)
				(thermal_bridge_width 0.5)
				(island_removal_mode 0)
			)
			(polygon
				(pts
					(xy 266.651232 -135.9027) (xy 266.143232 -135.9027) (xy 266.143232 -134.9121) (xy 266.651232 -134.9121)
				)
			)
		)
	)
	(footprint ""
		(layer "B.Cu")
		(at 318.543432 -145.034 -90)
		(property "Reference" "C4L4"
			(at 0 0 90)
			(layer "B.SilkS")
			(hide yes)
			(effects
				(font
					(size 1.27 1.27)
				)
				(justify mirror)
			)
		)
		(property "Value" ""
			(at 0 0 90)
			(layer "B.Fab")
			(effects
				(font
					(size 1.27 1.27)
				)
				(justify mirror)
			)
		)
		(duplicate_pad_numbers_are_jumpers no)
		(fp_poly
			(pts
				(xy 0.4953 -0.2032) (xy -0.4953 -0.2032) (xy -0.4953 1.6002) (xy 0.4953 1.6002)
			)
			(stroke
				(width 0)
				(type default)
			)
			(fill no)
			(layer "B.CrtYd")
		)
		(fp_line
			(start -0.4953 1.6002)
			(end 0.4953 1.6002)
			(stroke
				(width 0.1)
				(type default)
			)
			(layer "B.Fab")
		)
		(fp_line
			(start 0.4953 1.6002)
			(end 0.4953 -0.2032)
			(stroke
				(width 0.1)
				(type default)
			)
			(layer "B.Fab")
		)
		(fp_line
			(start -0.4953 -0.2032)
			(end -0.4953 1.6002)
			(stroke
				(width 0.1)
				(type default)
			)
			(layer "B.Fab")
		)
		(fp_line
			(start 0.4953 -0.2032)
			(end -0.4953 -0.2032)
			(stroke
				(width 0.1)
				(type default)
			)
			(layer "B.Fab")
		)
		(pad "1" smd rect
			(at 0 0 90)
			(size 0.762 0.889)
			(layers "B.Cu" "B.Mask" "B.Paste")
			(net "PVPP_DEF")
		)
		(pad "2" smd rect
			(at 0 1.397 90)
			(size 0.762 0.889)
			(layers "B.Cu" "B.Mask" "B.Paste")
			(net "GND")
		)
		(zone
			(layer "B.Cu")
			(hatch none 0.5)
			(connect_pads
				(clearance 0)
			)
			(min_thickness 0.25)
			(keepout
				(tracks not_allowed)
				(vias allowed)
				(pads allowed)
				(copperpour not_allowed)
				(footprints allowed)
			)
			(placement
				(enabled no)
				(sheetname "")
			)
			(fill
				(thermal_gap 0.5)
				(thermal_bridge_width 0.5)
				(island_removal_mode 0)
			)
			(polygon
				(pts
					(xy 318.098932 -144.653) (xy 318.098932 -145.415) (xy 317.590932 -145.415) (xy 317.590932 -144.653)
				)
			)
		)
	)
)
